# T6G (Grand Teton) — schematic netlist excerpt (pin names and nets, part order shuffled) for the footprints in the layout excerpt that follows; sources: Cadence DE-HDL packaged netlist, KiCad conversion of 04192023_DAF0TMB3IC0_F0TG_MB_C_brd_V02_OCP.brd

U46  PI3CSW12ZUAEX  IC  pkg UQFN10_0-5_2X1-5  page 186
  \1d+\  = SMB_RT_CPU0_P3_ROM_MUX_1D_SCL
  \1d-\  = SMB_RT_CPU0_P3_ROM_MUX_1D_SDA
  \2d+\  = SMB_RT_CPU0_P3_ROM_MUX_2D_SCL
  \2d-\  = SMB_RT_CPU0_P3_ROM_MUX_2D_SDA
  GND  = GND
  \oe#\  = RT_ROM_MUX7_OE_N
  \d-\  = SMB_RT_CPU0_P3_ROM_R_SDA
  \d+\  = SMB_RT_CPU0_P3_ROM_R_SCL
  S  = FM_SMB_RT_ROM_MUX7_SEL
  VDD  = P3V3_AUX

R4199  Q_RES  1K 1% CHIP  pkg 0402LF  page 235 : A = U270_0_ADD1 ; B = GND

(kicad_pcb
	(version 20260206)
	(generator "pcbnew")
	(generator_version "10.0")
	(general
		(thickness 1.6)
		(legacy_teardrops no)
	)
	(paper "A4")
	(title_block
		(title "04192023_DAF0TMB3IC0_F0TG_MB_C_brd_V02_OCP.brd")
		(comment 1 "Grand Teton / footprints 138-139 of 8354")
	)
	(layers
		(0 "F.Cu" signal "TOP")
		(4 "In1.Cu" signal "GND")
		(6 "In2.Cu" signal "IN1")
		(8 "In3.Cu" signal "GND1")
		(10 "In4.Cu" signal "IN2")
		(12 "In5.Cu" signal "GND2")
		(14 "In6.Cu" signal "IN3")
		(16 "In7.Cu" signal "GND3")
		(18 "In8.Cu" signal "VCC")
		(20 "In9.Cu" signal "VCC1")
		(22 "In10.Cu" signal "GND4")
		(24 "In11.Cu" signal "IN4")
		(26 "In12.Cu" signal "GND5")
		(28 "In13.Cu" signal "IN5")
		(30 "In14.Cu" signal "GND6")
		(32 "In15.Cu" signal "IN6")
		(34 "In16.Cu" signal "GND7")
		(2 "B.Cu" signal "BOTTOM")
		(9 "F.Adhes" user "F.Adhesive")
		(11 "B.Adhes" user "B.Adhesive")
		(13 "F.Paste" user "Package Geometry/Pastemask Top")
		(15 "B.Paste" user "Package Geometry/Pastemask Bottom")
		(5 "F.SilkS" user "Ref Des/Silkscreen Top")
		(7 "B.SilkS" user "Ref Des/Silkscreen Bottom")
		(1 "F.Mask" user "Board Geometry/Soldermask Top")
		(3 "B.Mask" user "Board Geometry/Soldermask Bottom")
		(17 "Dwgs.User" user "User.Drawings")
		(19 "Cmts.User" user "User.Comments")
		(21 "Eco1.User" user "User.Eco1")
		(23 "Eco2.User" user "User.Eco2")
		(25 "Edge.Cuts" user "Board Geometry/Outline")
		(27 "Margin" user)
		(31 "F.CrtYd" user "Package Geometry/Place Bound Top")
		(29 "B.CrtYd" user "Package Geometry/Place Bound Bottom")
		(35 "F.Fab" user "Ref Des/Assembly Top")
		(33 "B.Fab" user "Ref Des/Assembly Bottom")
	)
	(footprint ""
		(layer "F.Cu")
		(at 374.131586 -426.567854 -90)
		(property "Reference" "U46"
			(at -3.060192 -0.117602 0)
			(unlocked yes)
			(layer "F.SilkS")
			(effects
				(font
					(size 0.7874 0.5842)
					(thickness 0.1524)
				)
			)
		)
		(property "Value" ""
			(at 0 0 270)
			(layer "F.Fab")
			(effects
				(font
					(size 1.27 1.27)
				)
			)
		)
		(duplicate_pad_numbers_are_jumpers no)
		(fp_line
			(start -1.03378 1.284478)
			(end -1.03378 -1.284478)
			(stroke
				(width 0.1524)
				(type default)
			)
			(layer "F.SilkS")
		)
		(fp_line
			(start 1.03378 1.284478)
			(end -1.03378 1.284478)
			(stroke
				(width 0.1524)
				(type default)
			)
			(layer "F.SilkS")
		)
		(fp_line
			(start -1.03378 -1.284478)
			(end 1.03378 -1.284478)
			(stroke
				(width 0.1524)
				(type default)
			)
			(layer "F.SilkS")
		)
		(fp_line
			(start 1.03378 -1.284478)
			(end 1.03378 1.284478)
			(stroke
				(width 0.1524)
				(type default)
			)
			(layer "F.SilkS")
		)
		(fp_poly
			(pts
				(xy -1.201674 -0.750062) (xy -1.806702 -0.447548) (xy -1.806702 -1.052576)
			)
			(stroke
				(width 0)
				(type default)
			)
			(fill yes)
			(layer "F.SilkS")
		)
		(fp_line
			(start -0.774954 1.02489)
			(end -0.774954 -1.02489)
			(stroke
				(width 0.1)
				(type default)
			)
			(layer "F.Fab")
		)
		(fp_line
			(start 0.774954 1.02489)
			(end -0.774954 1.02489)
			(stroke
				(width 0.1)
				(type default)
			)
			(layer "F.Fab")
		)
		(fp_line
			(start -0.774954 -1.02489)
			(end 0.774954 -1.02489)
			(stroke
				(width 0.1)
				(type default)
			)
			(layer "F.Fab")
		)
		(fp_line
			(start 0.774954 -1.02489)
			(end 0.774954 1.02489)
			(stroke
				(width 0.1)
				(type default)
			)
			(layer "F.Fab")
		)
		(fp_poly
			(pts
				(xy -1.201674 -0.750062) (xy -1.806702 -0.447548) (xy -1.806702 -1.052576)
			)
			(stroke
				(width 0)
				(type default)
			)
			(fill yes)
			(layer "F.Fab")
		)
		(pad "1" smd rect
			(at -0.64008 -0.750062)
			(size 0.3048 0.5334)
			(layers "F.Cu" "F.Mask" "F.Paste")
			(net "SMB_RT_CPU0_P3_ROM_MUX_1D_SCL")
		)
		(pad "2" smd rect
			(at -0.64008 -0.249936)
			(size 0.254 0.5334)
			(layers "F.Cu" "F.Mask" "F.Paste")
			(net "SMB_RT_CPU0_P3_ROM_MUX_1D_SDA")
		)
		(pad "3" smd rect
			(at -0.64008 0.249936)
			(size 0.254 0.5334)
			(layers "F.Cu" "F.Mask" "F.Paste")
			(net "SMB_RT_CPU0_P3_ROM_MUX_2D_SCL")
		)
		(pad "4" smd rect
			(at -0.64008 0.750062)
			(size 0.3048 0.5334)
			(layers "F.Cu" "F.Mask" "F.Paste")
			(net "SMB_RT_CPU0_P3_ROM_MUX_2D_SDA")
		)
		(pad "5" smd rect
			(at 0 0.839978 270)
			(size 0.3302 0.635)
			(layers "F.Cu" "F.Mask" "F.Paste")
			(net "GND")
		)
		(pad "6" smd rect
			(at 0.64008 0.750062)
			(size 0.3048 0.5334)
			(layers "F.Cu" "F.Mask" "F.Paste")
			(net "RT_ROM_MUX7_OE_N")
		)
		(pad "7" smd rect
			(at 0.64008 0.249936)
			(size 0.254 0.5334)
			(layers "F.Cu" "F.Mask" "F.Paste")
			(net "SMB_RT_CPU0_P3_ROM_R_SDA")
		)
		(pad "8" smd rect
			(at 0.64008 -0.249936)
			(size 0.254 0.5334)
			(layers "F.Cu" "F.Mask" "F.Paste")
			(net "SMB_RT_CPU0_P3_ROM_R_SCL")
		)
		(pad "9" smd rect
			(at 0.64008 -0.750062)
			(size 0.3048 0.5334)
			(layers "F.Cu" "F.Mask" "F.Paste")
			(net "FM_SMB_RT_ROM_MUX7_SEL")
		)
		(pad "10" smd rect
			(at 0 -0.839978 270)
			(size 0.3302 0.635)
			(layers "F.Cu" "F.Mask" "F.Paste")
			(net "P3V3_AUX")
		)
	)
	(footprint ""
		(layer "F.Cu")
		(at 368.955066 -424.002962 90)
		(property "Reference" "R4199"
			(at 0 0 90)
			(layer "F.SilkS")
			(hide yes)
			(effects
				(font
					(size 1.27 1.27)
				)
			)
		)
		(property "Value" ""
			(at 0 0 90)
			(layer "F.Fab")
			(effects
				(font
					(size 1.27 1.27)
				)
			)
		)
		(duplicate_pad_numbers_are_jumpers no)
		(fp_line
			(start 0.7874 -0.4064)
			(end 0.7874 0.4064)
			(stroke
				(width 0.1524)
				(type default)
			)
			(layer "F.SilkS")
		)
		(fp_line
			(start -0.7874 -0.4064)
			(end 0.7874 -0.4064)
			(stroke
				(width 0.1524)
				(type default)
			)
			(layer "F.SilkS")
		)
		(fp_line
			(start 0.7874 0.4064)
			(end -0.7874 0.4064)
			(stroke
				(width 0.1524)
				(type default)
			)
			(layer "F.SilkS")
		)
		(fp_line
			(start -0.7874 0.4064)
			(end -0.7874 -0.4064)
			(stroke
				(width 0.1524)
				(type default)
			)
			(layer "F.SilkS")
		)
		(fp_line
			(start -0.12065 -0.305054)
			(end -0.12065 -0.2794)
			(stroke
				(width 0.1)
				(type default)
			)
			(layer "F.Fab")
		)
		(fp_line
			(start -0.67945 -0.305054)
			(end -0.12065 -0.305054)
			(stroke
				(width 0.1)
				(type default)
			)
			(layer "F.Fab")
		)
		(fp_line
			(start 0.67945 -0.3048)
			(end 0.67945 0.3048)
			(stroke
				(width 0.1)
				(type default)
			)
			(layer "F.Fab")
		)
		(fp_line
			(start 0.12065 -0.3048)
			(end 0.67945 -0.3048)
			(stroke
				(width 0.1)
				(type default)
			)
			(layer "F.Fab")
		)
		(fp_line
			(start 0.12065 -0.2794)
			(end 0.12065 -0.3048)
			(stroke
				(width 0.1)
				(type default)
			)
			(layer "F.Fab")
		)
		(fp_line
			(start -0.12065 -0.2794)
			(end 0.12065 -0.2794)
			(stroke
				(width 0.1)
				(type default)
			)
			(layer "F.Fab")
		)
		(fp_line
			(start 0.120396 0.2794)
			(end -0.12065 0.2794)
			(stroke
				(width 0.1)
				(type default)
			)
			(layer "F.Fab")
		)
		(fp_line
			(start -0.12065 0.2794)
			(end -0.12065 0.3048)
			(stroke
				(width 0.1)
				(type default)
			)
			(layer "F.Fab")
		)
		(fp_line
			(start 0.67945 0.3048)
			(end 0.120396 0.3048)
			(stroke
				(width 0.1)
				(type default)
			)
			(layer "F.Fab")
		)
		(fp_line
			(start 0.120396 0.3048)
			(end 0.120396 0.2794)
			(stroke
				(width 0.1)
				(type default)
			)
			(layer "F.Fab")
		)
		(fp_line
			(start -0.12065 0.3048)
			(end -0.67945 0.3048)
			(stroke
				(width 0.1)
				(type default)
			)
			(layer "F.Fab")
		)
		(fp_line
			(start -0.67945 0.3048)
			(end -0.67945 -0.305054)
			(stroke
				(width 0.1)
				(type default)
			)
			(layer "F.Fab")
		)
		(pad "1" smd circle
			(at -0.40005 0 90)
			(size 0 0)
			(layers "F.Cu" "F.Mask" "F.Paste")
			(net "U270_0_ADD1")
		)
		(pad "2" smd circle
			(at 0.40005 0 90)
			(size 0 0)
			(layers "F.Cu" "F.Mask" "F.Paste")
			(net "GND")
		)
	)
)
